(kicad_pcb
	(version 20260206)
	(generator "pcbnew")
	(generator_version "10.0")
	(general
		(thickness 1.6)
		(legacy_teardrops no)
	)
	(paper "A4")
	(title_block
		(title "Bryce Canyon_IOM_IOC_16318-2_OCP.brd")
		(comment 1 "Bryce Canyon / footprints 1034-1040 of 1605")
	)
	(layers
		(0 "F.Cu" signal "TOP")
		(4 "In1.Cu" signal "L2GND")
		(6 "In2.Cu" signal "L3")
		(8 "In3.Cu" signal "L4VCC")
		(10 "In4.Cu" signal "L5VCC")
		(12 "In5.Cu" signal "L6")
		(14 "In6.Cu" signal "L7GND")
		(2 "B.Cu" signal "BOTTOM")
		(9 "F.Adhes" user "F.Adhesive")
		(11 "B.Adhes" user "B.Adhesive")
		(13 "F.Paste" user "Package Geometry/Pastemask Top")
		(15 "B.Paste" user "Package Geometry/Pastemask Bottom")
		(5 "F.SilkS" user "Ref Des/Silkscreen Top")
		(7 "B.SilkS" user "Ref Des/Silkscreen Bottom")
		(1 "F.Mask" user "Board Geometry/Soldermask Top")
		(3 "B.Mask" user "Board Geometry/Soldermask Bottom")
		(17 "Dwgs.User" user "User.Drawings")
		(19 "Cmts.User" user "User.Comments")
		(21 "Eco1.User" user "User.Eco1")
		(23 "Eco2.User" user "User.Eco2")
		(25 "Edge.Cuts" user "Board Geometry/Outline")
		(27 "Margin" user)
		(31 "F.CrtYd" user "Package Geometry/Place Bound Top")
		(29 "B.CrtYd" user "Package Geometry/Place Bound Bottom")
		(35 "F.Fab" user "Ref Des/Assembly Top")
		(33 "B.Fab" user "Ref Des/Assembly Bottom")
	)
	(footprint ""
		(layer "B.Cu")
		(at 57.42305 -146.511264 -90)
		(property "Reference" "R360"
			(at 0 0 90)
			(layer "B.SilkS")
			(hide yes)
			(effects
				(font
					(size 1.27 1.27)
				)
				(justify mirror)
			)
		)
		(property "Value" "10KR2F-2-GP"
			(at -0.064008 -3.993896 270)
			(unlocked yes)
			(layer "B.Fab")
			(hide yes)
			(effects
				(font
					(size 1.016 1.016)
					(thickness 0.1524)
				)
				(justify mirror)
			)
		)
		(property "Device Type" "R402H16"
			(at -0.064008 -5.517896 270)
			(unlocked yes)
			(layer "B.Fab")
			(hide yes)
			(effects
				(font
					(size 1.016 1.016)
					(thickness 0.1524)
				)
				(justify mirror)
			)
		)
		(duplicate_pad_numbers_are_jumpers no)
		(fp_line
			(start -0.508 -0.9398)
			(end 0.508 -0.9398)
			(stroke
				(width 0.1524)
				(type default)
			)
			(layer "B.SilkS")
		)
		(fp_line
			(start 0.508 -0.9398)
			(end 0.508 0.9398)
			(stroke
				(width 0.1524)
				(type default)
			)
			(layer "B.SilkS")
		)
		(fp_rect
			(start 0.508 0.9398)
			(end -0.508 -0.9398)
			(stroke
				(width 0)
				(type default)
			)
			(fill no)
			(layer "B.CrtYd")
		)
		(fp_rect
			(start 0.508 0.9398)
			(end -0.508 -0.9398)
			(stroke
				(width 0)
				(type default)
			)
			(fill no)
			(layer "B.Fab")
		)
		(pad "1" smd custom
			(at 0 -0.4445 90)
			(size 0.1397 0.1397)
			(layers "B.Cu" "B.Mask" "B.Paste")
			(net "P3V3_STBY")
			(options
				(clearance outline)
				(anchor circle)
			)
			(primitives
				(gr_poly
					(pts
						(arc
							(start -0.1778 0.2794)
							(mid -0.249642 0.249642)
							(end -0.2794 0.1778)
						)
						(arc
							(start -0.2794 -0.1778)
							(mid -0.249642 -0.249642)
							(end -0.1778 -0.2794)
						)
						(arc
							(start 0.1778 -0.2794)
							(mid 0.249642 -0.249642)
							(end 0.2794 -0.1778)
						)
						(arc
							(start 0.2794 0.1778)
							(mid 0.249642 0.249642)
							(end 0.1778 0.2794)
						)
					)
					(width 0)
					(fill yes)
				)
			)
		)
		(pad "2" smd custom
			(at 0 0.4445 90)
			(size 0.1397 0.1397)
			(layers "B.Cu" "B.Mask" "B.Paste")
			(net "JTAG_BMC_TCK")
			(options
				(clearance outline)
				(anchor circle)
			)
			(primitives
				(gr_poly
					(pts
						(arc
							(start -0.1778 0.2794)
							(mid -0.249642 0.249642)
							(end -0.2794 0.1778)
						)
						(arc
							(start -0.2794 -0.1778)
							(mid -0.249642 -0.249642)
							(end -0.1778 -0.2794)
						)
						(arc
							(start 0.1778 -0.2794)
							(mid 0.249642 -0.249642)
							(end 0.2794 -0.1778)
						)
						(arc
							(start 0.2794 0.1778)
							(mid 0.249642 0.249642)
							(end 0.1778 0.2794)
						)
					)
					(width 0)
					(fill yes)
				)
			)
		)
	)
	(footprint ""
		(layer "B.Cu")
		(at 146.558 -17.145 90)
		(property "Reference" "U52"
			(at 0 0 90)
			(layer "B.SilkS")
			(hide yes)
			(effects
				(font
					(size 1.27 1.27)
				)
				(justify mirror)
			)
		)
		(property "Value" "SN74LVC1G08DCKR-GP"
			(at 2.3368 -8.6868 90)
			(unlocked yes)
			(layer "B.Fab")
			(hide yes)
			(effects
				(font
					(size 1.016 1.016)
					(thickness 0.1524)
				)
				(justify mirror)
			)
		)
		(property "Device Type" "SC70-5H44"
			(at 2.3114 -10.414 90)
			(unlocked yes)
			(layer "B.Fab")
			(hide yes)
			(effects
				(font
					(size 1.016 1.016)
					(thickness 0.1524)
				)
				(justify mirror)
			)
		)
		(duplicate_pad_numbers_are_jumpers no)
		(fp_line
			(start -0.6604 -1.8034)
			(end -1.3843 -1.8034)
			(stroke
				(width 0.3302)
				(type default)
			)
			(layer "B.SilkS")
		)
		(fp_line
			(start -1.3843 -1.8034)
			(end -1.3843 -1.1176)
			(stroke
				(width 0.3302)
				(type default)
			)
			(layer "B.SilkS")
		)
		(fp_line
			(start 1.27 -1.7018)
			(end -1.27 -1.7018)
			(stroke
				(width 0.1524)
				(type default)
			)
			(layer "B.SilkS")
		)
		(fp_line
			(start -1.27 -1.7018)
			(end -1.27 1.7018)
			(stroke
				(width 0.1524)
				(type default)
			)
			(layer "B.SilkS")
		)
		(fp_line
			(start 1.27 1.7018)
			(end 1.27 -1.7018)
			(stroke
				(width 0.1524)
				(type default)
			)
			(layer "B.SilkS")
		)
		(fp_line
			(start -1.27 1.7018)
			(end 1.27 1.7018)
			(stroke
				(width 0.1524)
				(type default)
			)
			(layer "B.SilkS")
		)
		(fp_rect
			(start 1.524 1.9558)
			(end -1.524 -1.9558)
			(stroke
				(width 0)
				(type default)
			)
			(fill no)
			(layer "B.CrtYd")
		)
		(fp_poly
			(pts
				(xy 1.524 -1.9558) (xy -1.524 -1.9558) (xy -1.524 1.9558) (xy 1.524 1.9558)
			)
			(stroke
				(width 0)
				(type default)
			)
			(fill no)
			(layer "B.Fab")
		)
		(pad "1" smd rect
			(at -0.65024 -0.8255 270)
			(size 0.4064 1.2192)
			(layers "B.Cu" "B.Mask" "B.Paste")
			(net "BMC_EXT2_LED_Y")
		)
		(pad "2" smd rect
			(at 0 -0.8255 270)
			(size 0.4064 1.2192)
			(layers "B.Cu" "B.Mask" "B.Paste")
			(net "EXT2_LED_YELLOW_D")
		)
		(pad "3" smd rect
			(at 0.65024 -0.8255 270)
			(size 0.4064 1.2192)
			(layers "B.Cu" "B.Mask" "B.Paste")
			(net "GND")
		)
		(pad "4" smd rect
			(at 0.65024 0.8255 270)
			(size 0.4064 1.2192)
			(layers "B.Cu" "B.Mask" "B.Paste")
			(net "EXT2_LED_YELLOW_G1")
		)
		(pad "5" smd rect
			(at -0.65024 0.8255 270)
			(size 0.4064 1.2192)
			(layers "B.Cu" "B.Mask" "B.Paste")
			(net "P3V3_STBY")
		)
	)
	(footprint ""
		(layer "B.Cu")
		(at 54.053232 -165.936676 90)
		(property "Reference" "R416"
			(at 0 0 90)
			(layer "B.SilkS")
			(hide yes)
			(effects
				(font
					(size 1.27 1.27)
				)
				(justify mirror)
			)
		)
		(property "Value" "1KR2F-3-GP"
			(at -0.064008 -3.993896 90)
			(unlocked yes)
			(layer "B.Fab")
			(hide yes)
			(effects
				(font
					(size 1.016 1.016)
					(thickness 0.1524)
				)
				(justify mirror)
			)
		)
		(property "Device Type" "R402H16"
			(at -0.064008 -5.517896 90)
			(unlocked yes)
			(layer "B.Fab")
			(hide yes)
			(effects
				(font
					(size 1.016 1.016)
					(thickness 0.1524)
				)
				(justify mirror)
			)
		)
		(duplicate_pad_numbers_are_jumpers no)
		(fp_line
			(start 0.508 -0.9398)
			(end 0.508 0.9398)
			(stroke
				(width 0.1524)
				(type default)
			)
			(layer "B.SilkS")
		)
		(fp_line
			(start -0.508 -0.9398)
			(end 0.508 -0.9398)
			(stroke
				(width 0.1524)
				(type default)
			)
			(layer "B.SilkS")
		)
		(fp_rect
			(start 0.508 0.9398)
			(end -0.508 -0.9398)
			(stroke
				(width 0)
				(type default)
			)
			(fill no)
			(layer "B.CrtYd")
		)
		(fp_rect
			(start 0.508 0.9398)
			(end -0.508 -0.9398)
			(stroke
				(width 0)
				(type default)
			)
			(fill no)
			(layer "B.Fab")
		)
		(pad "1" smd custom
			(at 0 -0.4445 270)
			(size 0.1397 0.1397)
			(layers "B.Cu" "B.Mask" "B.Paste")
			(net "ADC_P0V975")
			(options
				(clearance outline)
				(anchor circle)
			)
			(primitives
				(gr_poly
					(pts
						(arc
							(start -0.1778 0.2794)
							(mid -0.249642 0.249642)
							(end -0.2794 0.1778)
						)
						(arc
							(start -0.2794 -0.1778)
							(mid -0.249642 -0.249642)
							(end -0.1778 -0.2794)
						)
						(arc
							(start 0.1778 -0.2794)
							(mid 0.249642 -0.249642)
							(end 0.2794 -0.1778)
						)
						(arc
							(start 0.2794 0.1778)
							(mid 0.249642 0.249642)
							(end 0.1778 0.2794)
						)
					)
					(width 0)
					(fill yes)
				)
			)
		)
		(pad "2" smd custom
			(at 0 0.4445 270)
			(size 0.1397 0.1397)
			(layers "B.Cu" "B.Mask" "B.Paste")
			(net "GND")
			(options
				(clearance outline)
				(anchor circle)
			)
			(primitives
				(gr_poly
					(pts
						(arc
							(start -0.1778 0.2794)
							(mid -0.249642 0.249642)
							(end -0.2794 0.1778)
						)
						(arc
							(start -0.2794 -0.1778)
							(mid -0.249642 -0.249642)
							(end -0.1778 -0.2794)
						)
						(arc
							(start 0.1778 -0.2794)
							(mid 0.249642 -0.249642)
							(end 0.2794 -0.1778)
						)
						(arc
							(start 0.2794 0.1778)
							(mid 0.249642 0.249642)
							(end 0.1778 0.2794)
						)
					)
					(width 0)
					(fill yes)
				)
			)
		)
	)
	(footprint ""
		(layer "B.Cu")
		(at 55.790592 -146.507454)
		(property "Reference" "TP81"
			(at 0 0 0)
			(layer "B.SilkS")
			(hide yes)
			(effects
				(font
					(size 1.27 1.27)
				)
				(justify mirror)
			)
		)
		(property "Value" "TPAD28-2-GP"
			(at 0.0127 -1.6637 0)
			(unlocked yes)
			(layer "B.Fab")
			(hide yes)
			(effects
				(font
					(size 1.016 1.016)
					(thickness 0.1524)
				)
				(justify mirror)
			)
		)
		(property "Device Type" "TPAD28"
			(at 0.0127 -3.1877 0)
			(unlocked yes)
			(layer "B.Fab")
			(hide yes)
			(effects
				(font
					(size 1.016 1.016)
					(thickness 0.1524)
				)
				(justify mirror)
			)
		)
		(duplicate_pad_numbers_are_jumpers no)
		(fp_poly
			(pts
				(arc
					(start 0.3556 0)
					(mid -0.3556 0)
					(end 0.3556 0)
				)
			)
			(stroke
				(width 0)
				(type default)
			)
			(fill no)
			(layer "B.CrtYd")
		)
		(fp_poly
			(pts
				(arc
					(start 0.6096 0)
					(mid -0.6096 0)
					(end 0.6096 0)
				)
			)
			(stroke
				(width 0)
				(type default)
			)
			(fill no)
			(layer "B.Fab")
		)
		(pad "1" smd circle
			(at 0 0 180)
			(size 0.7112 0.7112)
			(layers "B.Cu" "B.Mask" "B.Paste")
			(net "JTAG_BMC_TCK")
		)
	)
	(footprint ""
		(layer "B.Cu")
		(at 16.6116 -139.1412 180)
		(property "Reference" "C68"
			(at 0 0 0)
			(layer "B.SilkS")
			(hide yes)
			(effects
				(font
					(size 1.27 1.27)
				)
				(justify mirror)
			)
		)
		(property "Value" "SCD1U16V2KX-3GP"
			(at -1.1811 -2.7051 180)
			(unlocked yes)
			(layer "B.Fab")
			(hide yes)
			(effects
				(font
					(size 1.016 1.016)
					(thickness 0.1524)
				)
				(justify mirror)
			)
		)
		(property "Device Type" "C402H22"
			(at -1.1811 -4.2291 180)
			(unlocked yes)
			(layer "B.Fab")
			(hide yes)
			(effects
				(font
					(size 1.016 1.016)
					(thickness 0.1524)
				)
				(justify mirror)
			)
		)
		(duplicate_pad_numbers_are_jumpers no)
		(fp_rect
			(start 0.4318 0.9525)
			(end -0.4318 -0.9525)
			(stroke
				(width 0)
				(type default)
			)
			(fill no)
			(layer "B.CrtYd")
		)
		(fp_rect
			(start 0.4318 0.9525)
			(end -0.4318 -0.9525)
			(stroke
				(width 0)
				(type default)
			)
			(fill no)
			(layer "B.Fab")
		)
		(pad "1" smd custom
			(at 0 -0.4445)
			(size 0.1524 0.1524)
			(layers "B.Cu" "B.Mask" "B.Paste")
			(net "GND")
			(options
				(clearance outline)
				(anchor circle)
			)
			(primitives
				(gr_poly
					(pts
						(arc
							(start 0.3048 0.2032)
							(mid 0.275042 0.275042)
							(end 0.2032 0.3048)
						)
						(arc
							(start -0.2032 0.3048)
							(mid -0.275042 0.275042)
							(end -0.3048 0.2032)
						)
						(arc
							(start -0.3048 -0.2032)
							(mid -0.275042 -0.275042)
							(end -0.2032 -0.3048)
						)
						(arc
							(start 0.2032 -0.3048)
							(mid 0.275042 -0.275042)
							(end 0.3048 -0.2032)
						)
					)
					(width 0)
					(fill yes)
				)
			)
		)
		(pad "2" smd custom
			(at 0 0.4445)
			(size 0.1524 0.1524)
			(layers "B.Cu" "B.Mask" "B.Paste")
			(net "DDR_VREF")
			(options
				(clearance outline)
				(anchor circle)
			)
			(primitives
				(gr_poly
					(pts
						(arc
							(start 0.3048 0.2032)
							(mid 0.275042 0.275042)
							(end 0.2032 0.3048)
						)
						(arc
							(start -0.2032 0.3048)
							(mid -0.275042 0.275042)
							(end -0.3048 0.2032)
						)
						(arc
							(start -0.3048 -0.2032)
							(mid -0.275042 -0.275042)
							(end -0.2032 -0.3048)
						)
						(arc
							(start 0.2032 -0.3048)
							(mid 0.275042 -0.275042)
							(end 0.3048 -0.2032)
						)
					)
					(width 0)
					(fill yes)
				)
			)
		)
	)
	(footprint ""
		(layer "B.Cu")
		(at 180.175408 -66.547746 -90)
		(property "Reference" "R573"
			(at 0 0 90)
			(layer "B.SilkS")
			(hide yes)
			(effects
				(font
					(size 1.27 1.27)
				)
				(justify mirror)
			)
		)
		(property "Value" "10KR2F-2-GP"
			(at -0.064008 -3.993896 270)
			(unlocked yes)
			(layer "B.Fab")
			(hide yes)
			(effects
				(font
					(size 1.016 1.016)
					(thickness 0.1524)
				)
				(justify mirror)
			)
		)
		(property "Device Type" "R402H16"
			(at -0.064008 -5.517896 270)
			(unlocked yes)
			(layer "B.Fab")
			(hide yes)
			(effects
				(font
					(size 1.016 1.016)
					(thickness 0.1524)
				)
				(justify mirror)
			)
		)
		(duplicate_pad_numbers_are_jumpers no)
		(fp_line
			(start -0.508 -0.9398)
			(end 0.508 -0.9398)
			(stroke
				(width 0.1524)
				(type default)
			)
			(layer "B.SilkS")
		)
		(fp_line
			(start 0.508 -0.9398)
			(end 0.508 0.9398)
			(stroke
				(width 0.1524)
				(type default)
			)
			(layer "B.SilkS")
		)
		(fp_rect
			(start 0.508 0.9398)
			(end -0.508 -0.9398)
			(stroke
				(width 0)
				(type default)
			)
			(fill no)
			(layer "B.CrtYd")
		)
		(fp_rect
			(start 0.508 0.9398)
			(end -0.508 -0.9398)
			(stroke
				(width 0)
				(type default)
			)
			(fill no)
			(layer "B.Fab")
		)
		(pad "1" smd custom
			(at 0 -0.4445 90)
			(size 0.1397 0.1397)
			(layers "B.Cu" "B.Mask" "B.Paste")
			(net "IOC_CLK_SEL1")
			(options
				(clearance outline)
				(anchor circle)
			)
			(primitives
				(gr_poly
					(pts
						(arc
							(start -0.1778 0.2794)
							(mid -0.249642 0.249642)
							(end -0.2794 0.1778)
						)
						(arc
							(start -0.2794 -0.1778)
							(mid -0.249642 -0.249642)
							(end -0.1778 -0.2794)
						)
						(arc
							(start 0.1778 -0.2794)
							(mid 0.249642 -0.249642)
							(end 0.2794 -0.1778)
						)
						(arc
							(start 0.2794 0.1778)
							(mid 0.249642 0.249642)
							(end 0.1778 0.2794)
						)
					)
					(width 0)
					(fill yes)
				)
			)
		)
		(pad "2" smd custom
			(at 0 0.4445 90)
			(size 0.1397 0.1397)
			(layers "B.Cu" "B.Mask" "B.Paste")
			(net "P1V8")
			(options
				(clearance outline)
				(anchor circle)
			)
			(primitives
				(gr_poly
					(pts
						(arc
							(start -0.1778 0.2794)
							(mid -0.249642 0.249642)
							(end -0.2794 0.1778)
						)
						(arc
							(start -0.2794 -0.1778)
							(mid -0.249642 -0.249642)
							(end -0.1778 -0.2794)
						)
						(arc
							(start 0.1778 -0.2794)
							(mid 0.249642 -0.249642)
							(end 0.2794 -0.1778)
						)
						(arc
							(start 0.2794 0.1778)
							(mid 0.249642 0.249642)
							(end 0.1778 0.2794)
						)
					)
					(width 0)
					(fill yes)
				)
			)
		)
	)
	(footprint ""
		(layer "B.Cu")
		(at 124.841 -9.779 -90)
		(property "Reference" "R437"
			(at 0 0 90)
			(layer "B.SilkS")
			(hide yes)
			(effects
				(font
					(size 1.27 1.27)
				)
				(justify mirror)
			)
		)
		(property "Value" "100KR2F-L1-GP"
			(at -0.064008 -3.993896 270)
			(unlocked yes)
			(layer "B.Fab")
			(hide yes)
			(effects
				(font
					(size 1.016 1.016)
					(thickness 0.1524)
				)
				(justify mirror)
			)
		)
		(property "Device Type" "R402H16"
			(at -0.064008 -5.517896 270)
			(unlocked yes)
			(layer "B.Fab")
			(hide yes)
			(effects
				(font
					(size 1.016 1.016)
					(thickness 0.1524)
				)
				(justify mirror)
			)
		)
		(duplicate_pad_numbers_are_jumpers no)
		(fp_line
			(start -0.508 -0.9398)
			(end 0.508 -0.9398)
			(stroke
				(width 0.1524)
				(type default)
			)
			(layer "B.SilkS")
		)
		(fp_line
			(start 0.508 -0.9398)
			(end 0.508 0.9398)
			(stroke
				(width 0.1524)
				(type default)
			)
			(layer "B.SilkS")
		)
		(fp_rect
			(start 0.508 0.9398)
			(end -0.508 -0.9398)
			(stroke
				(width 0)
				(type default)
			)
			(fill no)
			(layer "B.CrtYd")
		)
		(fp_rect
			(start 0.508 0.9398)
			(end -0.508 -0.9398)
			(stroke
				(width 0)
				(type default)
			)
			(fill no)
			(layer "B.Fab")
		)
		(pad "1" smd custom
			(at 0 -0.4445 90)
			(size 0.1397 0.1397)
			(layers "B.Cu" "B.Mask" "B.Paste")
			(net "P12V_STBY")
			(options
				(clearance outline)
				(anchor circle)
			)
			(primitives
				(gr_poly
					(pts
						(arc
							(start -0.1778 0.2794)
							(mid -0.249642 0.249642)
							(end -0.2794 0.1778)
						)
						(arc
							(start -0.2794 -0.1778)
							(mid -0.249642 -0.249642)
							(end -0.1778 -0.2794)
						)
						(arc
							(start 0.1778 -0.2794)
							(mid 0.249642 -0.249642)
							(end 0.2794 -0.1778)
						)
						(arc
							(start 0.2794 0.1778)
							(mid 0.249642 0.249642)
							(end 0.1778 0.2794)
						)
					)
					(width 0)
					(fill yes)
				)
			)
		)
		(pad "2" smd custom
			(at 0 0.4445 90)
			(size 0.1397 0.1397)
			(layers "B.Cu" "B.Mask" "B.Paste")
			(net "MB0_P12V_PWGIN_R")
			(options
				(clearance outline)
				(anchor circle)
			)
			(primitives
				(gr_poly
					(pts
						(arc
							(start -0.1778 0.2794)
							(mid -0.249642 0.249642)
							(end -0.2794 0.1778)
						)
						(arc
							(start -0.2794 -0.1778)
							(mid -0.249642 -0.249642)
							(end -0.1778 -0.2794)
						)
						(arc
							(start 0.1778 -0.2794)
							(mid 0.249642 -0.249642)
							(end 0.2794 -0.1778)
						)
						(arc
							(start 0.2794 0.1778)
							(mid 0.249642 0.249642)
							(end 0.1778 0.2794)
						)
					)
					(width 0)
					(fill yes)
				)
			)
		)
	)
)
